(kicad_pcb
	(version 20260206)
	(generator "pcbnew")
	(generator_version "10.0")
	(general
		(thickness 1.6)
		(legacy_teardrops no)
	)
	(paper "A4")
	(title_block
		(title "v1-chassis-manager — T6M_CM_d_v01_1031_1645.brd")
		(comment 1 "Open CloudServer (Microsoft) / footprints 186-195 of 2512")
	)
	(layers
		(0 "F.Cu" signal "TOP")
		(4 "In1.Cu" signal "GND1")
		(6 "In2.Cu" signal "IN1")
		(8 "In3.Cu" signal "VCC1")
		(10 "In4.Cu" signal "VCC2")
		(12 "In5.Cu" signal "GND2")
		(14 "In6.Cu" signal "IN2")
		(16 "In7.Cu" signal "IN3")
		(18 "In8.Cu" signal "GND3")
		(2 "B.Cu" signal "BOTTOM")
		(9 "F.Adhes" user "F.Adhesive")
		(11 "B.Adhes" user "B.Adhesive")
		(13 "F.Paste" user "Package Geometry/Pastemask Top")
		(15 "B.Paste" user "Package Geometry/Pastemask Bottom")
		(5 "F.SilkS" user "Ref Des/Silkscreen Top")
		(7 "B.SilkS" user "Ref Des/Silkscreen Bottom")
		(1 "F.Mask" user "Board Geometry/Soldermask Top")
		(3 "B.Mask" user "Board Geometry/Soldermask Bottom")
		(17 "Dwgs.User" user "User.Drawings")
		(19 "Cmts.User" user "User.Comments")
		(21 "Eco1.User" user "User.Eco1")
		(23 "Eco2.User" user "User.Eco2")
		(25 "Edge.Cuts" user "Board Geometry/Outline")
		(27 "Margin" user)
		(31 "F.CrtYd" user "Package Geometry/Place Bound Top")
		(29 "B.CrtYd" user "Package Geometry/Place Bound Bottom")
		(35 "F.Fab" user "Ref Des/Assembly Top")
		(33 "B.Fab" user "Ref Des/Assembly Bottom")
	)
	(footprint ""
		(layer "F.Cu")
		(at 175.000158 -26.75001)
		(property "Reference" "H7"
			(at 0 0 0)
			(layer "F.SilkS")
			(hide yes)
			(effects
				(font
					(size 1.27 1.27)
				)
			)
		)
		(property "Value" ""
			(at 0 0 0)
			(layer "F.Fab")
			(effects
				(font
					(size 1.27 1.27)
				)
			)
		)
		(duplicate_pad_numbers_are_jumpers no)
		(fp_poly
			(pts
				(arc
					(start 5.999988 4.99999)
					(mid 0 10.999978)
					(end -5.999988 4.99999)
				)
				(arc
					(start -5.999988 0)
					(mid 0 -5.999988)
					(end 5.999988 0)
				)
			)
			(stroke
				(width 0)
				(type default)
			)
			(fill no)
			(layer "B.CrtYd")
		)
		(fp_poly
			(pts
				(arc
					(start 5.999988 4.99999)
					(mid 0 10.999978)
					(end -5.999988 4.99999)
				)
				(arc
					(start -5.999988 0)
					(mid 0 -5.999988)
					(end 5.999988 0)
				)
			)
			(stroke
				(width 0)
				(type default)
			)
			(fill no)
			(layer "F.CrtYd")
		)
		(pad "" np_thru_hole circle
			(at 0 0)
			(size 3.81 3.81)
			(drill 3.81)
			(layers "*.Cu" "*.Mask")
			(clearance 0.381)
			(thermal_gap 0.381)
		)
	)
	(footprint ""
		(layer "F.Cu")
		(at 87.331804 -80.669638 180)
		(property "Reference" "C78"
			(at -2.485136 0.04445 0)
			(unlocked yes)
			(layer "F.SilkS")
			(effects
				(font
					(size 0.7874 0.5842)
					(thickness 0.1524)
				)
			)
		)
		(property "Value" ""
			(at 0 0 180)
			(layer "F.Fab")
			(effects
				(font
					(size 1.27 1.27)
				)
			)
		)
		(duplicate_pad_numbers_are_jumpers no)
		(fp_line
			(start 1.2954 0.5842)
			(end -1.2954 0.5842)
			(stroke
				(width 0.1524)
				(type default)
			)
			(layer "F.SilkS")
		)
		(fp_line
			(start 1.2954 -0.5842)
			(end 1.2954 0.5842)
			(stroke
				(width 0.1524)
				(type default)
			)
			(layer "F.SilkS")
		)
		(fp_line
			(start 0 -0.5842)
			(end 0 0.5842)
			(stroke
				(width 0.1524)
				(type default)
			)
			(layer "F.SilkS")
		)
		(fp_line
			(start -1.2954 0.5842)
			(end -1.2954 -0.5842)
			(stroke
				(width 0.1524)
				(type default)
			)
			(layer "F.SilkS")
		)
		(fp_line
			(start -1.2954 -0.5842)
			(end 1.2954 -0.5842)
			(stroke
				(width 0.1524)
				(type default)
			)
			(layer "F.SilkS")
		)
		(fp_poly
			(pts
				(xy 0.8636 -0.4572) (xy 0.8636 -0.3556) (xy 1.143 -0.3556) (xy 1.143 0.3556) (xy 0.8636 0.3556)
				(xy 0.8636 0.4572) (xy -0.8636 0.4572) (xy -0.8636 0.3556) (xy -1.143 0.3556) (xy -1.143 -0.3556)
				(xy -0.8636 -0.3556) (xy -0.8636 -0.4572)
			)
			(stroke
				(width 0)
				(type default)
			)
			(fill no)
			(layer "F.CrtYd")
		)
		(fp_line
			(start 0.884936 0.504952)
			(end -0.884936 0.504952)
			(stroke
				(width 0.1)
				(type default)
			)
			(layer "F.Fab")
		)
		(fp_line
			(start 0.884936 -0.504952)
			(end 0.884936 0.504952)
			(stroke
				(width 0.1)
				(type default)
			)
			(layer "F.Fab")
		)
		(fp_line
			(start -0.884936 0.504952)
			(end -0.884936 -0.504952)
			(stroke
				(width 0.1)
				(type default)
			)
			(layer "F.Fab")
		)
		(fp_line
			(start -0.884936 -0.504952)
			(end 0.884936 -0.504952)
			(stroke
				(width 0.1)
				(type default)
			)
			(layer "F.Fab")
		)
		(pad "1" smd rect
			(at 0.7366 0 270)
			(size 0.7112 0.8128)
			(layers "F.Cu" "F.Mask" "F.Paste")
			(net "P1V05_VCCPLLCPU1SIO_NODE1")
		)
		(pad "2" smd rect
			(at -0.7366 0 270)
			(size 0.7112 0.8128)
			(layers "F.Cu" "F.Mask" "F.Paste")
			(net "GND")
		)
	)
	(footprint ""
		(layer "F.Cu")
		(at 23.934928 -106.698796 180)
		(property "Reference" "PC61"
			(at 2.223008 -1.108202 0)
			(unlocked yes)
			(layer "F.SilkS")
			(effects
				(font
					(size 0.7874 0.5842)
					(thickness 0.1524)
				)
				(justify left)
			)
		)
		(property "Value" ""
			(at 0 0 180)
			(layer "F.Fab")
			(effects
				(font
					(size 1.27 1.27)
				)
			)
		)
		(duplicate_pad_numbers_are_jumpers no)
		(fp_line
			(start 0.7874 0.4064)
			(end -0.7874 0.4064)
			(stroke
				(width 0.1524)
				(type default)
			)
			(layer "F.SilkS")
		)
		(fp_line
			(start 0.7874 -0.4064)
			(end 0.7874 0.4064)
			(stroke
				(width 0.1524)
				(type default)
			)
			(layer "F.SilkS")
		)
		(fp_line
			(start 0 0.381)
			(end 0 -0.381)
			(stroke
				(width 0.1524)
				(type default)
			)
			(layer "F.SilkS")
		)
		(fp_line
			(start -0.7874 0.4064)
			(end -0.7874 -0.4064)
			(stroke
				(width 0.1524)
				(type default)
			)
			(layer "F.SilkS")
		)
		(fp_line
			(start -0.7874 -0.4064)
			(end 0.7874 -0.4064)
			(stroke
				(width 0.1524)
				(type default)
			)
			(layer "F.SilkS")
		)
		(fp_poly
			(pts
				(xy -0.5334 0.254) (xy -0.635 0.254) (xy -0.635 0.2286) (xy -0.635 -0.254) (xy -0.5334 -0.254) (xy -0.5334 -0.2794)
				(xy 0.5334 -0.2794) (xy 0.5334 -0.254) (xy 0.635 -0.254) (xy 0.635 0.254) (xy 0.5334 0.254) (xy 0.5334 0.2794)
				(xy -0.508 0.2794) (xy -0.5334 0.2794)
			)
			(stroke
				(width 0)
				(type default)
			)
			(fill no)
			(layer "F.CrtYd")
		)
		(pad "1" smd rect
			(at 0.40005 0 180)
			(size 0.4572 0.508)
			(layers "F.Cu" "F.Mask" "F.Paste")
			(net "P1V05_NODE1")
		)
		(pad "2" smd rect
			(at -0.40005 0 180)
			(size 0.4572 0.508)
			(layers "F.Cu" "F.Mask" "F.Paste")
			(net "GND")
		)
	)
	(footprint ""
		(layer "F.Cu")
		(at 101.558598 -131.539488 -90)
		(property "Reference" "PR50"
			(at 3.448812 2.180082 90)
			(unlocked yes)
			(layer "F.SilkS")
			(effects
				(font
					(size 0.7874 0.5842)
					(thickness 0.1524)
				)
				(justify left)
			)
		)
		(property "Value" ""
			(at 0 0 270)
			(layer "F.Fab")
			(effects
				(font
					(size 1.27 1.27)
				)
			)
		)
		(duplicate_pad_numbers_are_jumpers no)
		(fp_line
			(start -0.7874 0.4064)
			(end -0.7874 -0.4064)
			(stroke
				(width 0.1524)
				(type default)
			)
			(layer "F.SilkS")
		)
		(fp_line
			(start 0.7874 0.4064)
			(end -0.7874 0.4064)
			(stroke
				(width 0.1524)
				(type default)
			)
			(layer "F.SilkS")
		)
		(fp_line
			(start -0.7874 -0.4064)
			(end 0.7874 -0.4064)
			(stroke
				(width 0.1524)
				(type default)
			)
			(layer "F.SilkS")
		)
		(fp_line
			(start 0.7874 -0.4064)
			(end 0.7874 0.4064)
			(stroke
				(width 0.1524)
				(type default)
			)
			(layer "F.SilkS")
		)
		(fp_poly
			(pts
				(xy -0.508 0.2794) (xy -0.508 0.2286) (xy -0.635 0.2286) (xy -0.635 -0.254) (xy -0.5334 -0.254)
				(xy -0.5334 -0.2794) (xy 0.5334 -0.2794) (xy 0.5334 -0.254) (xy 0.635 -0.254) (xy 0.635 0.254) (xy 0.5334 0.254)
				(xy 0.5334 0.2794)
			)
			(stroke
				(width 0)
				(type default)
			)
			(fill no)
			(layer "F.CrtYd")
		)
		(pad "1" smd rect
			(at 0.40005 0 270)
			(size 0.4572 0.508)
			(layers "F.Cu" "F.Mask" "F.Paste")
			(net "P1V05_NODE1")
		)
		(pad "2" smd rect
			(at -0.40005 0 270)
			(size 0.4572 0.508)
			(layers "F.Cu" "F.Mask" "F.Paste")
			(net "SVID_CPU_NODE1_PVCCP_CLK")
		)
	)
	(footprint ""
		(layer "F.Cu")
		(at 152.662128 -150.14067 180)
		(property "Reference" "R597"
			(at 1.287272 3.575558 0)
			(unlocked yes)
			(layer "F.SilkS")
			(effects
				(font
					(size 0.635 0.4064)
					(thickness 0.1524)
				)
				(justify left)
			)
		)
		(property "Value" ""
			(at 0 0 180)
			(layer "F.Fab")
			(effects
				(font
					(size 1.27 1.27)
				)
			)
		)
		(duplicate_pad_numbers_are_jumpers no)
		(fp_line
			(start 0.7874 0.4064)
			(end -0.7874 0.4064)
			(stroke
				(width 0.1524)
				(type default)
			)
			(layer "F.SilkS")
		)
		(fp_line
			(start 0.7874 -0.4064)
			(end 0.7874 0.4064)
			(stroke
				(width 0.1524)
				(type default)
			)
			(layer "F.SilkS")
		)
		(fp_line
			(start -0.7874 0.4064)
			(end -0.7874 -0.4064)
			(stroke
				(width 0.1524)
				(type default)
			)
			(layer "F.SilkS")
		)
		(fp_line
			(start -0.7874 -0.4064)
			(end 0.7874 -0.4064)
			(stroke
				(width 0.1524)
				(type default)
			)
			(layer "F.SilkS")
		)
		(fp_poly
			(pts
				(xy -0.508 0.2794) (xy -0.508 0.2286) (xy -0.635 0.2286) (xy -0.635 -0.254) (xy -0.5334 -0.254)
				(xy -0.5334 -0.2794) (xy 0.5334 -0.2794) (xy 0.5334 -0.254) (xy 0.635 -0.254) (xy 0.635 0.254) (xy 0.5334 0.254)
				(xy 0.5334 0.2794)
			)
			(stroke
				(width 0)
				(type default)
			)
			(fill no)
			(layer "F.CrtYd")
		)
		(pad "1" smd rect
			(at 0.40005 0 180)
			(size 0.4572 0.508)
			(layers "F.Cu" "F.Mask" "F.Paste")
			(net "P3V3_NODE1")
		)
		(pad "2" smd rect
			(at -0.40005 0 180)
			(size 0.4572 0.508)
			(layers "F.Cu" "F.Mask" "F.Paste")
			(net "LAN2_DISABLE_N")
		)
	)
	(footprint ""
		(layer "F.Cu")
		(at 181.2036 -188.4172 -90)
		(property "Reference" "R1295"
			(at -1.1176 -0.10287 90)
			(unlocked yes)
			(layer "F.SilkS")
			(effects
				(font
					(size 0.7874 0.5842)
					(thickness 0.1524)
				)
				(justify left)
			)
		)
		(property "Value" ""
			(at 0 0 270)
			(layer "F.Fab")
			(effects
				(font
					(size 1.27 1.27)
				)
			)
		)
		(duplicate_pad_numbers_are_jumpers no)
		(fp_line
			(start -0.7874 0.4064)
			(end -0.7874 -0.4064)
			(stroke
				(width 0.1524)
				(type default)
			)
			(layer "F.SilkS")
		)
		(fp_line
			(start 0.7874 0.4064)
			(end -0.7874 0.4064)
			(stroke
				(width 0.1524)
				(type default)
			)
			(layer "F.SilkS")
		)
		(fp_line
			(start -0.7874 -0.4064)
			(end 0.7874 -0.4064)
			(stroke
				(width 0.1524)
				(type default)
			)
			(layer "F.SilkS")
		)
		(fp_line
			(start 0.7874 -0.4064)
			(end 0.7874 0.4064)
			(stroke
				(width 0.1524)
				(type default)
			)
			(layer "F.SilkS")
		)
		(fp_poly
			(pts
				(xy -0.508 0.2794) (xy -0.508 0.2286) (xy -0.635 0.2286) (xy -0.635 -0.254) (xy -0.5334 -0.254)
				(xy -0.5334 -0.2794) (xy 0.5334 -0.2794) (xy 0.5334 -0.254) (xy 0.635 -0.254) (xy 0.635 0.254) (xy 0.5334 0.254)
				(xy 0.5334 0.2794)
			)
			(stroke
				(width 0)
				(type default)
			)
			(fill no)
			(layer "F.CrtYd")
		)
		(pad "1" smd rect
			(at 0.40005 0 270)
			(size 0.4572 0.508)
			(layers "F.Cu" "F.Mask" "F.Paste")
			(net "POWER_SW1_PWR_CTR_12V")
		)
		(pad "2" smd rect
			(at -0.40005 0 270)
			(size 0.4572 0.508)
			(layers "F.Cu" "F.Mask" "F.Paste")
			(net "POWER_SW1_PWR_CTR_12V_R")
		)
	)
	(footprint ""
		(layer "F.Cu")
		(at 147.929346 -150.244048 90)
		(property "Reference" "R301"
			(at -4.65455 0.006858 90)
			(unlocked yes)
			(layer "F.SilkS")
			(effects
				(font
					(size 0.7874 0.5842)
					(thickness 0.1524)
				)
				(justify left)
			)
		)
		(property "Value" ""
			(at 0 0 90)
			(layer "F.Fab")
			(effects
				(font
					(size 1.27 1.27)
				)
			)
		)
		(duplicate_pad_numbers_are_jumpers no)
		(fp_line
			(start 0.7874 -0.4064)
			(end 0.7874 0.4064)
			(stroke
				(width 0.1524)
				(type default)
			)
			(layer "F.SilkS")
		)
		(fp_line
			(start -0.7874 -0.4064)
			(end 0.7874 -0.4064)
			(stroke
				(width 0.1524)
				(type default)
			)
			(layer "F.SilkS")
		)
		(fp_line
			(start 0.7874 0.4064)
			(end -0.7874 0.4064)
			(stroke
				(width 0.1524)
				(type default)
			)
			(layer "F.SilkS")
		)
		(fp_line
			(start -0.7874 0.4064)
			(end -0.7874 -0.4064)
			(stroke
				(width 0.1524)
				(type default)
			)
			(layer "F.SilkS")
		)
		(fp_poly
			(pts
				(xy -0.508 0.2794) (xy -0.508 0.2286) (xy -0.635 0.2286) (xy -0.635 -0.254) (xy -0.5334 -0.254)
				(xy -0.5334 -0.2794) (xy 0.5334 -0.2794) (xy 0.5334 -0.254) (xy 0.635 -0.254) (xy 0.635 0.254) (xy 0.5334 0.254)
				(xy 0.5334 0.2794)
			)
			(stroke
				(width 0)
				(type default)
			)
			(fill no)
			(layer "F.CrtYd")
		)
		(pad "1" smd rect
			(at 0.40005 0 90)
			(size 0.4572 0.508)
			(layers "F.Cu" "F.Mask" "F.Paste")
			(net "PCIE_SW_EEPROM_CLK")
		)
		(pad "2" smd rect
			(at -0.40005 0 90)
			(size 0.4572 0.508)
			(layers "F.Cu" "F.Mask" "F.Paste")
			(net "P3V3_NODE1")
		)
	)
	(footprint ""
		(layer "F.Cu")
		(at 158.48076 -188.126624 90)
		(property "Reference" "R1219"
			(at 5.519674 -3.661918 90)
			(unlocked yes)
			(layer "F.SilkS")
			(effects
				(font
					(size 0.7874 0.5842)
					(thickness 0.1524)
				)
				(justify left)
			)
		)
		(property "Value" ""
			(at 0 0 90)
			(layer "F.Fab")
			(effects
				(font
					(size 1.27 1.27)
				)
			)
		)
		(duplicate_pad_numbers_are_jumpers no)
		(fp_line
			(start 0.7874 -0.4064)
			(end 0.7874 0.4064)
			(stroke
				(width 0.1524)
				(type default)
			)
			(layer "F.SilkS")
		)
		(fp_line
			(start -0.7874 -0.4064)
			(end 0.7874 -0.4064)
			(stroke
				(width 0.1524)
				(type default)
			)
			(layer "F.SilkS")
		)
		(fp_line
			(start 0.7874 0.4064)
			(end -0.7874 0.4064)
			(stroke
				(width 0.1524)
				(type default)
			)
			(layer "F.SilkS")
		)
		(fp_line
			(start -0.7874 0.4064)
			(end -0.7874 -0.4064)
			(stroke
				(width 0.1524)
				(type default)
			)
			(layer "F.SilkS")
		)
		(fp_poly
			(pts
				(xy -0.508 0.2794) (xy -0.508 0.2286) (xy -0.635 0.2286) (xy -0.635 -0.254) (xy -0.5334 -0.254)
				(xy -0.5334 -0.2794) (xy 0.5334 -0.2794) (xy 0.5334 -0.254) (xy 0.635 -0.254) (xy 0.635 0.254) (xy 0.5334 0.254)
				(xy 0.5334 0.2794)
			)
			(stroke
				(width 0)
				(type default)
			)
			(fill no)
			(layer "F.CrtYd")
		)
		(pad "1" smd rect
			(at 0.40005 0 90)
			(size 0.4572 0.508)
			(layers "F.Cu" "F.Mask" "F.Paste")
			(net "FAN1_TACH_R")
		)
		(pad "2" smd rect
			(at -0.40005 0 90)
			(size 0.4572 0.508)
			(layers "F.Cu" "F.Mask" "F.Paste")
			(net "GND")
		)
	)
	(footprint ""
		(layer "F.Cu")
		(at 182.2196 -188.4172 -90)
		(property "Reference" "R1293"
			(at -1.1176 -0.10287 90)
			(unlocked yes)
			(layer "F.SilkS")
			(effects
				(font
					(size 0.7874 0.5842)
					(thickness 0.1524)
				)
				(justify left)
			)
		)
		(property "Value" ""
			(at 0 0 270)
			(layer "F.Fab")
			(effects
				(font
					(size 1.27 1.27)
				)
			)
		)
		(duplicate_pad_numbers_are_jumpers no)
		(fp_line
			(start -0.7874 0.4064)
			(end -0.7874 -0.4064)
			(stroke
				(width 0.1524)
				(type default)
			)
			(layer "F.SilkS")
		)
		(fp_line
			(start 0.7874 0.4064)
			(end -0.7874 0.4064)
			(stroke
				(width 0.1524)
				(type default)
			)
			(layer "F.SilkS")
		)
		(fp_line
			(start -0.7874 -0.4064)
			(end 0.7874 -0.4064)
			(stroke
				(width 0.1524)
				(type default)
			)
			(layer "F.SilkS")
		)
		(fp_line
			(start 0.7874 -0.4064)
			(end 0.7874 0.4064)
			(stroke
				(width 0.1524)
				(type default)
			)
			(layer "F.SilkS")
		)
		(fp_poly
			(pts
				(xy -0.508 0.2794) (xy -0.508 0.2286) (xy -0.635 0.2286) (xy -0.635 -0.254) (xy -0.5334 -0.254)
				(xy -0.5334 -0.2794) (xy 0.5334 -0.2794) (xy 0.5334 -0.254) (xy 0.635 -0.254) (xy 0.635 0.254) (xy 0.5334 0.254)
				(xy 0.5334 0.2794)
			)
			(stroke
				(width 0)
				(type default)
			)
			(fill no)
			(layer "F.CrtYd")
		)
		(pad "1" smd rect
			(at 0.40005 0 270)
			(size 0.4572 0.508)
			(layers "F.Cu" "F.Mask" "F.Paste")
			(net "POWER_SW1_PWR_CTR_12V")
		)
		(pad "2" smd rect
			(at -0.40005 0 270)
			(size 0.4572 0.508)
			(layers "F.Cu" "F.Mask" "F.Paste")
			(net "POWER_SW1_PWR_CTR_12V_R")
		)
	)
	(footprint ""
		(layer "F.Cu")
		(at 34.800286 -8.56869 90)
		(property "Reference" "PR40"
			(at -1.92659 -9.192514 90)
			(unlocked yes)
			(layer "F.SilkS")
			(effects
				(font
					(size 0.7874 0.5842)
					(thickness 0.1524)
				)
				(justify left)
			)
		)
		(property "Value" ""
			(at 0 0 90)
			(layer "F.Fab")
			(effects
				(font
					(size 1.27 1.27)
				)
			)
		)
		(duplicate_pad_numbers_are_jumpers no)
		(fp_line
			(start 0.7874 -0.4064)
			(end 0.7874 0.4064)
			(stroke
				(width 0.1524)
				(type default)
			)
			(layer "F.SilkS")
		)
		(fp_line
			(start -0.7874 -0.4064)
			(end 0.7874 -0.4064)
			(stroke
				(width 0.1524)
				(type default)
			)
			(layer "F.SilkS")
		)
		(fp_line
			(start 0.7874 0.4064)
			(end -0.7874 0.4064)
			(stroke
				(width 0.1524)
				(type default)
			)
			(layer "F.SilkS")
		)
		(fp_line
			(start -0.7874 0.4064)
			(end -0.7874 -0.4064)
			(stroke
				(width 0.1524)
				(type default)
			)
			(layer "F.SilkS")
		)
		(fp_poly
			(pts
				(xy -0.508 0.2794) (xy -0.508 0.2286) (xy -0.635 0.2286) (xy -0.635 -0.254) (xy -0.5334 -0.254)
				(xy -0.5334 -0.2794) (xy 0.5334 -0.2794) (xy 0.5334 -0.254) (xy 0.635 -0.254) (xy 0.635 0.254) (xy 0.5334 0.254)
				(xy 0.5334 0.2794)
			)
			(stroke
				(width 0)
				(type default)
			)
			(fill no)
			(layer "F.CrtYd")
		)
		(pad "1" smd rect
			(at 0.40005 0 90)
			(size 0.4572 0.508)
			(layers "F.Cu" "F.Mask" "F.Paste")
			(net "PV_VDDR_NODE1_V0")
		)
		(pad "2" smd rect
			(at -0.40005 0 90)
			(size 0.4572 0.508)
			(layers "F.Cu" "F.Mask" "F.Paste")
			(net "PV_VDDR_NODE1_VREF")
		)
	)
)
